#ISCELL
  mstr_misc dns *
  *
#ISCELL
  pure_quanta quanta_title_block_c *
  *
#ISCELL
  pure_quanta_power cad_note *
  *
#CELL
  pure_quanta q_cap *
  page422_i10
#ISCELL
  pure_quanta_power p1v0 *
  page422_i11
#CELL
  pure_quanta q_cap *
  page422_i12
#CELL
  pure_quanta q_cap *
  page422_i13
#ISCELL
  pure_quanta_power universal_gnd *
  page422_i14
#CELL
  pure_quanta q_cap *
  page422_i15
#CELL
  pure_quanta q_cap *
  page422_i16
#CELL
  pure_quanta q_cap *
  page422_i17
#CELL
  pure_quanta q_cap *
  page422_i18
#CELL
  pure_quanta q_cap *
  page422_i19
#CELL
  pure_quanta q_cap *
  page422_i20
#CELL
  pure_quanta q_res *
  page422_i21
#CELL
  pure_quanta q_res *
  page422_i22
#CELL
  pure_quanta q_inductor *
  page422_i23
#ISCELL
  pure_quanta_power p1v0 *
  page422_i24
#CELL
  pure_quanta q_cap *
  page422_i25
#CELL
  pure_quanta q_cap *
  page422_i26
#CELL
  pure_quanta q_cap *
  page422_i27
#ISCELL
  pure_quanta_power universal_gnd *
  page422_i28
#CELL
  pure_quanta q_cap *
  page422_i29
#ISCELL
  pure_quanta_power p1v0 *
  page422_i3
#CELL
  pure_quanta q_inductor *
  page422_i30
#ISCELL
  pure_quanta_power vcc_core *
  page422_i31
#ISCELL
  pure_quanta_power vcc_core *
  page422_i33
#CELL
  pure_quanta q_cap *
  page422_i34
#CELL
  pure_quanta q_cap *
  page422_i35
#CELL
  pure_quanta q_cap *
  page422_i36
#ISCELL
  pure_quanta_power universal_gnd *
  page422_i38
#CELL
  pure_quanta q_cap *
  page422_i39
#CELL
  pure_quanta q_res *
  page422_i4
#CELL
  pure_quanta q_cap *
  page422_i40
#CELL
  pure_quanta q_cap *
  page422_i41
#CELL
  pure_quanta q_cap *
  page422_i42
#CELL
  pure_quanta q_cap *
  page422_i43
#CELL
  pure_quanta q_cap *
  page422_i44
#CELL
  pure_quanta q_cap *
  page422_i45
#CELL
  pure_quanta q_cap *
  page422_i46
#CELL
  pure_quanta q_cap *
  page422_i47
#CELL
  pure_quanta q_cap *
  page422_i48
#CELL
  pure_quanta q_cap *
  page422_i49
#CELL
  pure_quanta q_res *
  page422_i5
#CELL
  pure_quanta q_cap *
  page422_i50
#CELL
  pure_quanta q_cap *
  page422_i51
#CELL
  pure_quanta q_cap *
  page422_i52
#CELL
  pure_quanta q_cap *
  page422_i54
#CELL
  pure_quanta q_cap *
  page422_i55
#CELL
  pure_quanta q_cap *
  page422_i56
#CELL
  pure_quanta q_cap *
  page422_i57
#CELL
  pure_quanta q_cap *
  page422_i58
#CELL
  pure_quanta q_cap *
  page422_i59
#CELL
  pure_quanta q_cap *
  page422_i6
#CELL
  pure_quanta q_cap *
  page422_i60
#CELL
  pure_quanta q_cap *
  page422_i61
#CELL
  pure_quanta q_cap *
  page422_i62
#CELL
  pure_quanta q_cap *
  page422_i63
#CELL
  pure_quanta q_cap *
  page422_i64
#CELL
  pure_quanta q_cap *
  page422_i65
#CELL
  pure_quanta q_cap *
  page422_i66
#ISCELL
  pure_quanta_power universal_gnd *
  page422_i67
#CELL
  pure_quanta q_cap *
  page422_i68
#CELL
  pure_quanta q_cap *
  page422_i69
#CELL
  pure_quanta q_cap *
  page422_i7
#ISCELL
  pure_quanta_power universal_gnd *
  page422_i71
#CELL
  pure_quanta q_cap *
  page422_i72
#CELL
  pure_quanta q_cap *
  page422_i73
#CELL
  pure_quanta q_cap *
  page422_i74
#CELL
  pure_quanta q_cap *
  page422_i75
#ISCELL
  pure_quanta_power vcc_core *
  page422_i76
#CELL
  pure_quanta q_cap *
  page422_i77
#CELL
  pure_quanta q_cap *
  page422_i78
#CELL
  pure_quanta q_cap *
  page422_i79
#ISCELL
  pure_quanta_power universal_gnd *
  page422_i8
#CELL
  pure_quanta q_cap *
  page422_i80
#CELL
  pure_quanta q_cap *
  page422_i81
#CELL
  pure_quanta q_cap *
  page422_i82
#CELL
  pure_quanta q_cap *
  page422_i83
#CELL
  pure_quanta q_cap *
  page422_i84
#ISCELL
  pure_quanta_power universal_gnd *
  page422_i85
#CELL
  pure_quanta q_cap *
  page422_i86
#CELL
  pure_quanta q_cap *
  page422_i87
#CELL
  pure_quanta q_inductor *
  page422_i88
#CELL
  pure_quanta q_res *
  page422_i89
#CELL
  pure_quanta q_cap *
  page422_i9
#CELL
  pure_quanta q_cap *
  page422_i90
#CELL
  pure_quanta q_cap *
  page422_i91
#CELL
  pure_quanta q_cap *
  page422_i92
#CELL
  pure_quanta q_cap *
  page422_i93
#CELL
  pure_quanta q_capp *
  page422_i94
#CELL
  pure_quanta q_capp *
  page422_i95
#CELL
  pure_quanta q_cap *
  page422_i96
